(kicad_pcb
	(version 20260206)
	(generator "pcbnew")
	(generator_version "10.0")
	(general
		(thickness 1.6)
		(legacy_teardrops no)
	)
	(paper "A4")
	(title_block
		(title "04192023_DAF0TMB3IC0_F0TG_MB_C_brd_V02_OCP.brd")
		(comment 1 "Grand Teton / footprints 679-686 of 8354")
	)
	(layers
		(0 "F.Cu" signal "TOP")
		(4 "In1.Cu" signal "GND")
		(6 "In2.Cu" signal "IN1")
		(8 "In3.Cu" signal "GND1")
		(10 "In4.Cu" signal "IN2")
		(12 "In5.Cu" signal "GND2")
		(14 "In6.Cu" signal "IN3")
		(16 "In7.Cu" signal "GND3")
		(18 "In8.Cu" signal "VCC")
		(20 "In9.Cu" signal "VCC1")
		(22 "In10.Cu" signal "GND4")
		(24 "In11.Cu" signal "IN4")
		(26 "In12.Cu" signal "GND5")
		(28 "In13.Cu" signal "IN5")
		(30 "In14.Cu" signal "GND6")
		(32 "In15.Cu" signal "IN6")
		(34 "In16.Cu" signal "GND7")
		(2 "B.Cu" signal "BOTTOM")
		(9 "F.Adhes" user "F.Adhesive")
		(11 "B.Adhes" user "B.Adhesive")
		(13 "F.Paste" user "Package Geometry/Pastemask Top")
		(15 "B.Paste" user "Package Geometry/Pastemask Bottom")
		(5 "F.SilkS" user "Ref Des/Silkscreen Top")
		(7 "B.SilkS" user "Ref Des/Silkscreen Bottom")
		(1 "F.Mask" user "Board Geometry/Soldermask Top")
		(3 "B.Mask" user "Board Geometry/Soldermask Bottom")
		(17 "Dwgs.User" user "User.Drawings")
		(19 "Cmts.User" user "User.Comments")
		(21 "Eco1.User" user "User.Eco1")
		(23 "Eco2.User" user "User.Eco2")
		(25 "Edge.Cuts" user "Board Geometry/Outline")
		(27 "Margin" user)
		(31 "F.CrtYd" user "Package Geometry/Place Bound Top")
		(29 "B.CrtYd" user "Package Geometry/Place Bound Bottom")
		(35 "F.Fab" user "Ref Des/Assembly Top")
		(33 "B.Fab" user "Ref Des/Assembly Bottom")
	)
	(footprint ""
		(layer "F.Cu")
		(at 100.457 -77.216)
		(property "Reference" "R1166"
			(at 0 0 0)
			(layer "F.SilkS")
			(hide yes)
			(effects
				(font
					(size 1.27 1.27)
				)
			)
		)
		(property "Value" ""
			(at 0 0 0)
			(layer "F.Fab")
			(effects
				(font
					(size 1.27 1.27)
				)
			)
		)
		(duplicate_pad_numbers_are_jumpers no)
		(fp_line
			(start -0.7874 -0.4064)
			(end 0.7874 -0.4064)
			(stroke
				(width 0.1524)
				(type default)
			)
			(layer "F.SilkS")
		)
		(fp_line
			(start -0.7874 0.4064)
			(end -0.7874 -0.4064)
			(stroke
				(width 0.1524)
				(type default)
			)
			(layer "F.SilkS")
		)
		(fp_line
			(start 0.7874 -0.4064)
			(end 0.7874 0.4064)
			(stroke
				(width 0.1524)
				(type default)
			)
			(layer "F.SilkS")
		)
		(fp_line
			(start 0.7874 0.4064)
			(end -0.7874 0.4064)
			(stroke
				(width 0.1524)
				(type default)
			)
			(layer "F.SilkS")
		)
		(fp_line
			(start -0.67945 -0.305054)
			(end -0.12065 -0.305054)
			(stroke
				(width 0.1)
				(type default)
			)
			(layer "F.Fab")
		)
		(fp_line
			(start -0.67945 0.3048)
			(end -0.67945 -0.305054)
			(stroke
				(width 0.1)
				(type default)
			)
			(layer "F.Fab")
		)
		(fp_line
			(start -0.12065 -0.305054)
			(end -0.12065 -0.2794)
			(stroke
				(width 0.1)
				(type default)
			)
			(layer "F.Fab")
		)
		(fp_line
			(start -0.12065 -0.2794)
			(end 0.12065 -0.2794)
			(stroke
				(width 0.1)
				(type default)
			)
			(layer "F.Fab")
		)
		(fp_line
			(start -0.12065 0.2794)
			(end -0.12065 0.3048)
			(stroke
				(width 0.1)
				(type default)
			)
			(layer "F.Fab")
		)
		(fp_line
			(start -0.12065 0.3048)
			(end -0.67945 0.3048)
			(stroke
				(width 0.1)
				(type default)
			)
			(layer "F.Fab")
		)
		(fp_line
			(start 0.120396 0.2794)
			(end -0.12065 0.2794)
			(stroke
				(width 0.1)
				(type default)
			)
			(layer "F.Fab")
		)
		(fp_line
			(start 0.120396 0.3048)
			(end 0.120396 0.2794)
			(stroke
				(width 0.1)
				(type default)
			)
			(layer "F.Fab")
		)
		(fp_line
			(start 0.12065 -0.3048)
			(end 0.67945 -0.3048)
			(stroke
				(width 0.1)
				(type default)
			)
			(layer "F.Fab")
		)
		(fp_line
			(start 0.12065 -0.2794)
			(end 0.12065 -0.3048)
			(stroke
				(width 0.1)
				(type default)
			)
			(layer "F.Fab")
		)
		(fp_line
			(start 0.67945 -0.3048)
			(end 0.67945 0.3048)
			(stroke
				(width 0.1)
				(type default)
			)
			(layer "F.Fab")
		)
		(fp_line
			(start 0.67945 0.3048)
			(end 0.120396 0.3048)
			(stroke
				(width 0.1)
				(type default)
			)
			(layer "F.Fab")
		)
		(pad "1" smd circle
			(at -0.40005 0)
			(size 0 0)
			(layers "F.Cu" "F.Mask" "F.Paste")
			(net "P12V_OCP_V3_2_PLD_R_PWRGD")
		)
		(pad "2" smd circle
			(at 0.40005 0)
			(size 0 0)
			(layers "F.Cu" "F.Mask" "F.Paste")
			(net "P12V_OCP_V3_2_PLD_PWRGD")
		)
	)
	(footprint ""
		(layer "F.Cu")
		(at 125.405896 -370.57203 -90)
		(property "Reference" "C1529"
			(at 0 0 270)
			(layer "F.SilkS")
			(hide yes)
			(effects
				(font
					(size 1.27 1.27)
				)
			)
		)
		(property "Value" ""
			(at 0 0 270)
			(layer "F.Fab")
			(effects
				(font
					(size 1.27 1.27)
				)
			)
		)
		(duplicate_pad_numbers_are_jumpers no)
		(fp_line
			(start -0.299974 0.150114)
			(end -0.299974 -0.150114)
			(stroke
				(width 0.1)
				(type default)
			)
			(layer "F.Fab")
		)
		(fp_line
			(start 0.299974 0.150114)
			(end -0.299974 0.150114)
			(stroke
				(width 0.1)
				(type default)
			)
			(layer "F.Fab")
		)
		(fp_line
			(start -0.299974 -0.150114)
			(end 0.299974 -0.150114)
			(stroke
				(width 0.1)
				(type default)
			)
			(layer "F.Fab")
		)
		(fp_line
			(start 0.299974 -0.150114)
			(end 0.299974 0.150114)
			(stroke
				(width 0.1)
				(type default)
			)
			(layer "F.Fab")
		)
		(pad "1" smd rect
			(at -0.2667 0 270)
			(size 0.3048 0.381)
			(layers "F.Cu" "F.Mask" "F.Paste")
			(net "P5E_CPU1_P3_TX_C_DP<9>")
		)
		(pad "2" smd rect
			(at 0.2667 0 270)
			(size 0.3048 0.381)
			(layers "F.Cu" "F.Mask" "F.Paste")
			(net "P5E_CPU1_P3_TX_DP<9>")
		)
	)
	(footprint ""
		(layer "F.Cu")
		(at 165.576758 -352.27006 90)
		(property "Reference" "PR393"
			(at 0 0 90)
			(layer "F.SilkS")
			(hide yes)
			(effects
				(font
					(size 1.27 1.27)
				)
			)
		)
		(property "Value" ""
			(at 0 0 90)
			(layer "F.Fab")
			(effects
				(font
					(size 1.27 1.27)
				)
			)
		)
		(duplicate_pad_numbers_are_jumpers no)
		(fp_line
			(start 0.7874 -0.4064)
			(end 0.7874 0.4064)
			(stroke
				(width 0.1524)
				(type default)
			)
			(layer "F.SilkS")
		)
		(fp_line
			(start -0.7874 -0.4064)
			(end 0.7874 -0.4064)
			(stroke
				(width 0.1524)
				(type default)
			)
			(layer "F.SilkS")
		)
		(fp_line
			(start 0.7874 0.4064)
			(end -0.7874 0.4064)
			(stroke
				(width 0.1524)
				(type default)
			)
			(layer "F.SilkS")
		)
		(fp_line
			(start -0.7874 0.4064)
			(end -0.7874 -0.4064)
			(stroke
				(width 0.1524)
				(type default)
			)
			(layer "F.SilkS")
		)
		(fp_line
			(start -0.12065 -0.305054)
			(end -0.12065 -0.2794)
			(stroke
				(width 0.1)
				(type default)
			)
			(layer "F.Fab")
		)
		(fp_line
			(start -0.67945 -0.305054)
			(end -0.12065 -0.305054)
			(stroke
				(width 0.1)
				(type default)
			)
			(layer "F.Fab")
		)
		(fp_line
			(start 0.67945 -0.3048)
			(end 0.67945 0.3048)
			(stroke
				(width 0.1)
				(type default)
			)
			(layer "F.Fab")
		)
		(fp_line
			(start 0.12065 -0.3048)
			(end 0.67945 -0.3048)
			(stroke
				(width 0.1)
				(type default)
			)
			(layer "F.Fab")
		)
		(fp_line
			(start 0.12065 -0.2794)
			(end 0.12065 -0.3048)
			(stroke
				(width 0.1)
				(type default)
			)
			(layer "F.Fab")
		)
		(fp_line
			(start -0.12065 -0.2794)
			(end 0.12065 -0.2794)
			(stroke
				(width 0.1)
				(type default)
			)
			(layer "F.Fab")
		)
		(fp_line
			(start 0.120396 0.2794)
			(end -0.12065 0.2794)
			(stroke
				(width 0.1)
				(type default)
			)
			(layer "F.Fab")
		)
		(fp_line
			(start -0.12065 0.2794)
			(end -0.12065 0.3048)
			(stroke
				(width 0.1)
				(type default)
			)
			(layer "F.Fab")
		)
		(fp_line
			(start 0.67945 0.3048)
			(end 0.120396 0.3048)
			(stroke
				(width 0.1)
				(type default)
			)
			(layer "F.Fab")
		)
		(fp_line
			(start 0.120396 0.3048)
			(end 0.120396 0.2794)
			(stroke
				(width 0.1)
				(type default)
			)
			(layer "F.Fab")
		)
		(fp_line
			(start -0.12065 0.3048)
			(end -0.67945 0.3048)
			(stroke
				(width 0.1)
				(type default)
			)
			(layer "F.Fab")
		)
		(fp_line
			(start -0.67945 0.3048)
			(end -0.67945 -0.305054)
			(stroke
				(width 0.1)
				(type default)
			)
			(layer "F.Fab")
		)
		(pad "1" smd circle
			(at -0.40005 0 90)
			(size 0 0)
			(layers "F.Cu" "F.Mask" "F.Paste")
			(net "PVDD11_S3_P1_VCC")
		)
		(pad "2" smd circle
			(at 0.40005 0 90)
			(size 0 0)
			(layers "F.Cu" "F.Mask" "F.Paste")
			(net "P3V3_AUX")
		)
	)
	(footprint ""
		(layer "F.Cu")
		(at 59.135518 -143.656558 -90)
		(property "Reference" "PR399"
			(at 0 0 270)
			(layer "F.SilkS")
			(hide yes)
			(effects
				(font
					(size 1.27 1.27)
				)
			)
		)
		(property "Value" ""
			(at 0 0 270)
			(layer "F.Fab")
			(effects
				(font
					(size 1.27 1.27)
				)
			)
		)
		(duplicate_pad_numbers_are_jumpers no)
		(fp_line
			(start -0.7874 0.4064)
			(end -0.7874 -0.4064)
			(stroke
				(width 0.1524)
				(type default)
			)
			(layer "F.SilkS")
		)
		(fp_line
			(start 0.7874 0.4064)
			(end -0.7874 0.4064)
			(stroke
				(width 0.1524)
				(type default)
			)
			(layer "F.SilkS")
		)
		(fp_line
			(start -0.7874 -0.4064)
			(end 0.7874 -0.4064)
			(stroke
				(width 0.1524)
				(type default)
			)
			(layer "F.SilkS")
		)
		(fp_line
			(start 0.7874 -0.4064)
			(end 0.7874 0.4064)
			(stroke
				(width 0.1524)
				(type default)
			)
			(layer "F.SilkS")
		)
		(fp_line
			(start -0.67945 0.3048)
			(end -0.67945 -0.305054)
			(stroke
				(width 0.1)
				(type default)
			)
			(layer "F.Fab")
		)
		(fp_line
			(start -0.12065 0.3048)
			(end -0.67945 0.3048)
			(stroke
				(width 0.1)
				(type default)
			)
			(layer "F.Fab")
		)
		(fp_line
			(start 0.120396 0.3048)
			(end 0.120396 0.2794)
			(stroke
				(width 0.1)
				(type default)
			)
			(layer "F.Fab")
		)
		(fp_line
			(start 0.67945 0.3048)
			(end 0.120396 0.3048)
			(stroke
				(width 0.1)
				(type default)
			)
			(layer "F.Fab")
		)
		(fp_line
			(start -0.12065 0.2794)
			(end -0.12065 0.3048)
			(stroke
				(width 0.1)
				(type default)
			)
			(layer "F.Fab")
		)
		(fp_line
			(start 0.120396 0.2794)
			(end -0.12065 0.2794)
			(stroke
				(width 0.1)
				(type default)
			)
			(layer "F.Fab")
		)
		(fp_line
			(start -0.12065 -0.2794)
			(end 0.12065 -0.2794)
			(stroke
				(width 0.1)
				(type default)
			)
			(layer "F.Fab")
		)
		(fp_line
			(start 0.12065 -0.2794)
			(end 0.12065 -0.3048)
			(stroke
				(width 0.1)
				(type default)
			)
			(layer "F.Fab")
		)
		(fp_line
			(start 0.12065 -0.3048)
			(end 0.67945 -0.3048)
			(stroke
				(width 0.1)
				(type default)
			)
			(layer "F.Fab")
		)
		(fp_line
			(start 0.67945 -0.3048)
			(end 0.67945 0.3048)
			(stroke
				(width 0.1)
				(type default)
			)
			(layer "F.Fab")
		)
		(fp_line
			(start -0.67945 -0.305054)
			(end -0.12065 -0.305054)
			(stroke
				(width 0.1)
				(type default)
			)
			(layer "F.Fab")
		)
		(fp_line
			(start -0.12065 -0.305054)
			(end -0.12065 -0.2794)
			(stroke
				(width 0.1)
				(type default)
			)
			(layer "F.Fab")
		)
		(pad "1" smd circle
			(at -0.40005 0 270)
			(size 0 0)
			(layers "F.Cu" "F.Mask" "F.Paste")
			(net "GND")
		)
		(pad "2" smd circle
			(at 0.40005 0 270)
			(size 0 0)
			(layers "F.Cu" "F.Mask" "F.Paste")
			(net "PVDD18_SS_P1_RGND")
		)
	)
	(footprint ""
		(layer "F.Cu")
		(at 307.498496 -378.95403 -90)
		(property "Reference" "C921"
			(at 0 0 270)
			(layer "F.SilkS")
			(hide yes)
			(effects
				(font
					(size 1.27 1.27)
				)
			)
		)
		(property "Value" ""
			(at 0 0 270)
			(layer "F.Fab")
			(effects
				(font
					(size 1.27 1.27)
				)
			)
		)
		(duplicate_pad_numbers_are_jumpers no)
		(fp_line
			(start -0.299974 0.150114)
			(end -0.299974 -0.150114)
			(stroke
				(width 0.1)
				(type default)
			)
			(layer "F.Fab")
		)
		(fp_line
			(start 0.299974 0.150114)
			(end -0.299974 0.150114)
			(stroke
				(width 0.1)
				(type default)
			)
			(layer "F.Fab")
		)
		(fp_line
			(start -0.299974 -0.150114)
			(end 0.299974 -0.150114)
			(stroke
				(width 0.1)
				(type default)
			)
			(layer "F.Fab")
		)
		(fp_line
			(start 0.299974 -0.150114)
			(end 0.299974 0.150114)
			(stroke
				(width 0.1)
				(type default)
			)
			(layer "F.Fab")
		)
		(pad "1" smd rect
			(at -0.2667 0 270)
			(size 0.3048 0.381)
			(layers "F.Cu" "F.Mask" "F.Paste")
			(net "P5E_CPU0_P0_TX_C_DP<6>")
		)
		(pad "2" smd rect
			(at 0.2667 0 270)
			(size 0.3048 0.381)
			(layers "F.Cu" "F.Mask" "F.Paste")
			(net "P5E_CPU0_P0_TX_DP<6>")
		)
	)
	(footprint ""
		(layer "F.Cu")
		(at 307.391562 -351.927922)
		(property "Reference" "PR85"
			(at 0 0 0)
			(layer "F.SilkS")
			(hide yes)
			(effects
				(font
					(size 1.27 1.27)
				)
			)
		)
		(property "Value" ""
			(at 0 0 0)
			(layer "F.Fab")
			(effects
				(font
					(size 1.27 1.27)
				)
			)
		)
		(duplicate_pad_numbers_are_jumpers no)
		(fp_line
			(start -0.7874 -0.4064)
			(end 0.7874 -0.4064)
			(stroke
				(width 0.1524)
				(type default)
			)
			(layer "F.SilkS")
		)
		(fp_line
			(start -0.7874 0.4064)
			(end -0.7874 -0.4064)
			(stroke
				(width 0.1524)
				(type default)
			)
			(layer "F.SilkS")
		)
		(fp_line
			(start 0.7874 -0.4064)
			(end 0.7874 0.4064)
			(stroke
				(width 0.1524)
				(type default)
			)
			(layer "F.SilkS")
		)
		(fp_line
			(start 0.7874 0.4064)
			(end -0.7874 0.4064)
			(stroke
				(width 0.1524)
				(type default)
			)
			(layer "F.SilkS")
		)
		(fp_line
			(start -0.67945 -0.305054)
			(end -0.12065 -0.305054)
			(stroke
				(width 0.1)
				(type default)
			)
			(layer "F.Fab")
		)
		(fp_line
			(start -0.67945 0.3048)
			(end -0.67945 -0.305054)
			(stroke
				(width 0.1)
				(type default)
			)
			(layer "F.Fab")
		)
		(fp_line
			(start -0.12065 -0.305054)
			(end -0.12065 -0.2794)
			(stroke
				(width 0.1)
				(type default)
			)
			(layer "F.Fab")
		)
		(fp_line
			(start -0.12065 -0.2794)
			(end 0.12065 -0.2794)
			(stroke
				(width 0.1)
				(type default)
			)
			(layer "F.Fab")
		)
		(fp_line
			(start -0.12065 0.2794)
			(end -0.12065 0.3048)
			(stroke
				(width 0.1)
				(type default)
			)
			(layer "F.Fab")
		)
		(fp_line
			(start -0.12065 0.3048)
			(end -0.67945 0.3048)
			(stroke
				(width 0.1)
				(type default)
			)
			(layer "F.Fab")
		)
		(fp_line
			(start 0.120396 0.2794)
			(end -0.12065 0.2794)
			(stroke
				(width 0.1)
				(type default)
			)
			(layer "F.Fab")
		)
		(fp_line
			(start 0.120396 0.3048)
			(end 0.120396 0.2794)
			(stroke
				(width 0.1)
				(type default)
			)
			(layer "F.Fab")
		)
		(fp_line
			(start 0.12065 -0.3048)
			(end 0.67945 -0.3048)
			(stroke
				(width 0.1)
				(type default)
			)
			(layer "F.Fab")
		)
		(fp_line
			(start 0.12065 -0.2794)
			(end 0.12065 -0.3048)
			(stroke
				(width 0.1)
				(type default)
			)
			(layer "F.Fab")
		)
		(fp_line
			(start 0.67945 -0.3048)
			(end 0.67945 0.3048)
			(stroke
				(width 0.1)
				(type default)
			)
			(layer "F.Fab")
		)
		(fp_line
			(start 0.67945 0.3048)
			(end 0.120396 0.3048)
			(stroke
				(width 0.1)
				(type default)
			)
			(layer "F.Fab")
		)
		(pad "1" smd circle
			(at -0.40005 0)
			(size 0 0)
			(layers "F.Cu" "F.Mask" "F.Paste")
			(net "PVDDCR_CPU1_P0_LSET4")
		)
		(pad "2" smd circle
			(at 0.40005 0)
			(size 0 0)
			(layers "F.Cu" "F.Mask" "F.Paste")
			(net "GND")
		)
	)
	(footprint ""
		(layer "F.Cu")
		(at 389.522208 -173.314868)
		(property "Reference" "H38"
			(at -5.712206 2.34696 0)
			(unlocked yes)
			(layer "F.SilkS")
			(effects
				(font
					(size 0.7874 0.5842)
					(thickness 0.1524)
				)
				(justify left)
			)
		)
		(property "Value" ""
			(at 0 0 0)
			(layer "F.Fab")
			(effects
				(font
					(size 1.27 1.27)
				)
			)
		)
		(duplicate_pad_numbers_are_jumpers no)
		(pad "1" thru_hole circle
			(at 0 0)
			(size 6.1976 6.1976)
			(drill 3.7338)
			(layers "*.Cu" "*.Mask")
			(remove_unused_layers no)
			(net "GND")
			(clearance -0.9779)
			(padstack
				(mode front_inner_back)
				(layer "Inner"
					(shape circle)
					(size 5.5372 5.5372)
					(clearance -0.6477)
				)
				(layer "B.Cu"
					(shape circle)
					(size 6.1976 6.1976)
					(clearance -0.9779)
				)
			)
		)
	)
	(footprint ""
		(layer "F.Cu")
		(at 185.799222 -23.113492)
		(property "Reference" "PR4000"
			(at 0 0 0)
			(layer "F.SilkS")
			(hide yes)
			(effects
				(font
					(size 1.27 1.27)
				)
			)
		)
		(property "Value" ""
			(at 0 0 0)
			(layer "F.Fab")
			(effects
				(font
					(size 1.27 1.27)
				)
			)
		)
		(duplicate_pad_numbers_are_jumpers no)
		(fp_line
			(start -0.7874 -0.4064)
			(end 0.7874 -0.4064)
			(stroke
				(width 0.1524)
				(type default)
			)
			(layer "F.SilkS")
		)
		(fp_line
			(start -0.7874 0.4064)
			(end -0.7874 -0.4064)
			(stroke
				(width 0.1524)
				(type default)
			)
			(layer "F.SilkS")
		)
		(fp_line
			(start 0.7874 -0.4064)
			(end 0.7874 0.4064)
			(stroke
				(width 0.1524)
				(type default)
			)
			(layer "F.SilkS")
		)
		(fp_line
			(start 0.7874 0.4064)
			(end -0.7874 0.4064)
			(stroke
				(width 0.1524)
				(type default)
			)
			(layer "F.SilkS")
		)
		(fp_line
			(start -0.67945 -0.305054)
			(end -0.12065 -0.305054)
			(stroke
				(width 0.1)
				(type default)
			)
			(layer "F.Fab")
		)
		(fp_line
			(start -0.67945 0.3048)
			(end -0.67945 -0.305054)
			(stroke
				(width 0.1)
				(type default)
			)
			(layer "F.Fab")
		)
		(fp_line
			(start -0.12065 -0.305054)
			(end -0.12065 -0.2794)
			(stroke
				(width 0.1)
				(type default)
			)
			(layer "F.Fab")
		)
		(fp_line
			(start -0.12065 -0.2794)
			(end 0.12065 -0.2794)
			(stroke
				(width 0.1)
				(type default)
			)
			(layer "F.Fab")
		)
		(fp_line
			(start -0.12065 0.2794)
			(end -0.12065 0.3048)
			(stroke
				(width 0.1)
				(type default)
			)
			(layer "F.Fab")
		)
		(fp_line
			(start -0.12065 0.3048)
			(end -0.67945 0.3048)
			(stroke
				(width 0.1)
				(type default)
			)
			(layer "F.Fab")
		)
		(fp_line
			(start 0.120396 0.2794)
			(end -0.12065 0.2794)
			(stroke
				(width 0.1)
				(type default)
			)
			(layer "F.Fab")
		)
		(fp_line
			(start 0.120396 0.3048)
			(end 0.120396 0.2794)
			(stroke
				(width 0.1)
				(type default)
			)
			(layer "F.Fab")
		)
		(fp_line
			(start 0.12065 -0.3048)
			(end 0.67945 -0.3048)
			(stroke
				(width 0.1)
				(type default)
			)
			(layer "F.Fab")
		)
		(fp_line
			(start 0.12065 -0.2794)
			(end 0.12065 -0.3048)
			(stroke
				(width 0.1)
				(type default)
			)
			(layer "F.Fab")
		)
		(fp_line
			(start 0.67945 -0.3048)
			(end 0.67945 0.3048)
			(stroke
				(width 0.1)
				(type default)
			)
			(layer "F.Fab")
		)
		(fp_line
			(start 0.67945 0.3048)
			(end 0.120396 0.3048)
			(stroke
				(width 0.1)
				(type default)
			)
			(layer "F.Fab")
		)
		(pad "1" smd circle
			(at -0.40005 0)
			(size 0 0)
			(layers "F.Cu" "F.Mask" "F.Paste")
			(net "P12V_AUX")
		)
		(pad "2" smd circle
			(at 0.40005 0)
			(size 0 0)
			(layers "F.Cu" "F.Mask" "F.Paste")
			(net "P12V_SCM_UV")
		)
	)
)
